# T6G (Grand Teton) — schematic netlist excerpt (pin names and nets, part order shuffled) for the footprints in the layout excerpt that follows; sources: Cadence DE-HDL packaged netlist, KiCad conversion of 04192023_DAF0TMB3IC0_F0TG_MB_C_brd_V02_OCP.brd

R448  Q_RES  4.7K 5% EMPTY  pkg 0402LF  page 28 : A = CPU0_SLP_S5_N ; B = PVDD18_S5_P0
PR320  Q_RES  8.87K 1% EMPTY  pkg 0402LF  page 194 : A = GND ; B = PVDDCR_CPU0_P0_LSET1
C9105  Q_CAP_DIFFBUS  DIFF BUS_0.22UF 6.3V 20% X6S  pkg C0201  page 67 : \1\ = P3E_CPU1_P4_TX_C_DN<0> ; \2\ = P3E_CPU1_P4_TX_DN<0>

(kicad_pcb
	(version 20260206)
	(generator "pcbnew")
	(generator_version "10.0")
	(general
		(thickness 1.6)
		(legacy_teardrops no)
	)
	(paper "A4")
	(title_block
		(title "04192023_DAF0TMB3IC0_F0TG_MB_C_brd_V02_OCP.brd")
		(comment 1 "Grand Teton / footprints 365-367 of 8354")
	)
	(layers
		(0 "F.Cu" signal "TOP")
		(4 "In1.Cu" signal "GND")
		(6 "In2.Cu" signal "IN1")
		(8 "In3.Cu" signal "GND1")
		(10 "In4.Cu" signal "IN2")
		(12 "In5.Cu" signal "GND2")
		(14 "In6.Cu" signal "IN3")
		(16 "In7.Cu" signal "GND3")
		(18 "In8.Cu" signal "VCC")
		(20 "In9.Cu" signal "VCC1")
		(22 "In10.Cu" signal "GND4")
		(24 "In11.Cu" signal "IN4")
		(26 "In12.Cu" signal "GND5")
		(28 "In13.Cu" signal "IN5")
		(30 "In14.Cu" signal "GND6")
		(32 "In15.Cu" signal "IN6")
		(34 "In16.Cu" signal "GND7")
		(2 "B.Cu" signal "BOTTOM")
		(9 "F.Adhes" user "F.Adhesive")
		(11 "B.Adhes" user "B.Adhesive")
		(13 "F.Paste" user "Package Geometry/Pastemask Top")
		(15 "B.Paste" user "Package Geometry/Pastemask Bottom")
		(5 "F.SilkS" user "Ref Des/Silkscreen Top")
		(7 "B.SilkS" user "Ref Des/Silkscreen Bottom")
		(1 "F.Mask" user "Board Geometry/Soldermask Top")
		(3 "B.Mask" user "Board Geometry/Soldermask Bottom")
		(17 "Dwgs.User" user "User.Drawings")
		(19 "Cmts.User" user "User.Comments")
		(21 "Eco1.User" user "User.Eco1")
		(23 "Eco2.User" user "User.Eco2")
		(25 "Edge.Cuts" user "Board Geometry/Outline")
		(27 "Margin" user)
		(31 "F.CrtYd" user "Package Geometry/Place Bound Top")
		(29 "B.CrtYd" user "Package Geometry/Place Bound Bottom")
		(35 "F.Fab" user "Ref Des/Assembly Top")
		(33 "B.Fab" user "Ref Des/Assembly Bottom")
	)
	(footprint ""
		(layer "F.Cu")
		(at 365.618522 -172.559726)
		(property "Reference" "PR320"
			(at 0 0 0)
			(layer "F.SilkS")
			(hide yes)
			(effects
				(font
					(size 1.27 1.27)
				)
			)
		)
		(property "Value" ""
			(at 0 0 0)
			(layer "F.Fab")
			(effects
				(font
					(size 1.27 1.27)
				)
			)
		)
		(duplicate_pad_numbers_are_jumpers no)
		(fp_line
			(start -0.7874 -0.4064)
			(end 0.7874 -0.4064)
			(stroke
				(width 0.1524)
				(type default)
			)
			(layer "F.SilkS")
		)
		(fp_line
			(start -0.7874 0.4064)
			(end -0.7874 -0.4064)
			(stroke
				(width 0.1524)
				(type default)
			)
			(layer "F.SilkS")
		)
		(fp_line
			(start 0.7874 -0.4064)
			(end 0.7874 0.4064)
			(stroke
				(width 0.1524)
				(type default)
			)
			(layer "F.SilkS")
		)
		(fp_line
			(start 0.7874 0.4064)
			(end -0.7874 0.4064)
			(stroke
				(width 0.1524)
				(type default)
			)
			(layer "F.SilkS")
		)
		(fp_line
			(start -0.67945 -0.305054)
			(end -0.12065 -0.305054)
			(stroke
				(width 0.1)
				(type default)
			)
			(layer "F.Fab")
		)
		(fp_line
			(start -0.67945 0.3048)
			(end -0.67945 -0.305054)
			(stroke
				(width 0.1)
				(type default)
			)
			(layer "F.Fab")
		)
		(fp_line
			(start -0.12065 -0.305054)
			(end -0.12065 -0.2794)
			(stroke
				(width 0.1)
				(type default)
			)
			(layer "F.Fab")
		)
		(fp_line
			(start -0.12065 -0.2794)
			(end 0.12065 -0.2794)
			(stroke
				(width 0.1)
				(type default)
			)
			(layer "F.Fab")
		)
		(fp_line
			(start -0.12065 0.2794)
			(end -0.12065 0.3048)
			(stroke
				(width 0.1)
				(type default)
			)
			(layer "F.Fab")
		)
		(fp_line
			(start -0.12065 0.3048)
			(end -0.67945 0.3048)
			(stroke
				(width 0.1)
				(type default)
			)
			(layer "F.Fab")
		)
		(fp_line
			(start 0.120396 0.2794)
			(end -0.12065 0.2794)
			(stroke
				(width 0.1)
				(type default)
			)
			(layer "F.Fab")
		)
		(fp_line
			(start 0.120396 0.3048)
			(end 0.120396 0.2794)
			(stroke
				(width 0.1)
				(type default)
			)
			(layer "F.Fab")
		)
		(fp_line
			(start 0.12065 -0.3048)
			(end 0.67945 -0.3048)
			(stroke
				(width 0.1)
				(type default)
			)
			(layer "F.Fab")
		)
		(fp_line
			(start 0.12065 -0.2794)
			(end 0.12065 -0.3048)
			(stroke
				(width 0.1)
				(type default)
			)
			(layer "F.Fab")
		)
		(fp_line
			(start 0.67945 -0.3048)
			(end 0.67945 0.3048)
			(stroke
				(width 0.1)
				(type default)
			)
			(layer "F.Fab")
		)
		(fp_line
			(start 0.67945 0.3048)
			(end 0.120396 0.3048)
			(stroke
				(width 0.1)
				(type default)
			)
			(layer "F.Fab")
		)
		(pad "1" smd circle
			(at -0.40005 0)
			(size 0 0)
			(layers "F.Cu" "F.Mask" "F.Paste")
			(net "GND")
		)
		(pad "2" smd circle
			(at 0.40005 0)
			(size 0 0)
			(layers "F.Cu" "F.Mask" "F.Paste")
			(net "PVDDCR_CPU0_P0_LSET1")
		)
	)
	(footprint ""
		(layer "F.Cu")
		(at 404.158958 -321.002152 90)
		(property "Reference" "R448"
			(at 0 0 90)
			(layer "F.SilkS")
			(hide yes)
			(effects
				(font
					(size 1.27 1.27)
				)
			)
		)
		(property "Value" ""
			(at 0 0 90)
			(layer "F.Fab")
			(effects
				(font
					(size 1.27 1.27)
				)
			)
		)
		(duplicate_pad_numbers_are_jumpers no)
		(fp_line
			(start 0.7874 -0.4064)
			(end 0.7874 0.4064)
			(stroke
				(width 0.1524)
				(type default)
			)
			(layer "F.SilkS")
		)
		(fp_line
			(start -0.7874 -0.4064)
			(end 0.7874 -0.4064)
			(stroke
				(width 0.1524)
				(type default)
			)
			(layer "F.SilkS")
		)
		(fp_line
			(start 0.7874 0.4064)
			(end -0.7874 0.4064)
			(stroke
				(width 0.1524)
				(type default)
			)
			(layer "F.SilkS")
		)
		(fp_line
			(start -0.7874 0.4064)
			(end -0.7874 -0.4064)
			(stroke
				(width 0.1524)
				(type default)
			)
			(layer "F.SilkS")
		)
		(fp_line
			(start -0.12065 -0.305054)
			(end -0.12065 -0.2794)
			(stroke
				(width 0.1)
				(type default)
			)
			(layer "F.Fab")
		)
		(fp_line
			(start -0.67945 -0.305054)
			(end -0.12065 -0.305054)
			(stroke
				(width 0.1)
				(type default)
			)
			(layer "F.Fab")
		)
		(fp_line
			(start 0.67945 -0.3048)
			(end 0.67945 0.3048)
			(stroke
				(width 0.1)
				(type default)
			)
			(layer "F.Fab")
		)
		(fp_line
			(start 0.12065 -0.3048)
			(end 0.67945 -0.3048)
			(stroke
				(width 0.1)
				(type default)
			)
			(layer "F.Fab")
		)
		(fp_line
			(start 0.12065 -0.2794)
			(end 0.12065 -0.3048)
			(stroke
				(width 0.1)
				(type default)
			)
			(layer "F.Fab")
		)
		(fp_line
			(start -0.12065 -0.2794)
			(end 0.12065 -0.2794)
			(stroke
				(width 0.1)
				(type default)
			)
			(layer "F.Fab")
		)
		(fp_line
			(start 0.120396 0.2794)
			(end -0.12065 0.2794)
			(stroke
				(width 0.1)
				(type default)
			)
			(layer "F.Fab")
		)
		(fp_line
			(start -0.12065 0.2794)
			(end -0.12065 0.3048)
			(stroke
				(width 0.1)
				(type default)
			)
			(layer "F.Fab")
		)
		(fp_line
			(start 0.67945 0.3048)
			(end 0.120396 0.3048)
			(stroke
				(width 0.1)
				(type default)
			)
			(layer "F.Fab")
		)
		(fp_line
			(start 0.120396 0.3048)
			(end 0.120396 0.2794)
			(stroke
				(width 0.1)
				(type default)
			)
			(layer "F.Fab")
		)
		(fp_line
			(start -0.12065 0.3048)
			(end -0.67945 0.3048)
			(stroke
				(width 0.1)
				(type default)
			)
			(layer "F.Fab")
		)
		(fp_line
			(start -0.67945 0.3048)
			(end -0.67945 -0.305054)
			(stroke
				(width 0.1)
				(type default)
			)
			(layer "F.Fab")
		)
		(pad "1" smd circle
			(at -0.40005 0 90)
			(size 0 0)
			(layers "F.Cu" "F.Mask" "F.Paste")
			(net "CPU0_SLP_S5_N")
		)
		(pad "2" smd circle
			(at 0.40005 0 90)
			(size 0 0)
			(layers "F.Cu" "F.Mask" "F.Paste")
			(net "PVDD18_S5_P0")
		)
	)
	(footprint ""
		(layer "F.Cu")
		(at 180.528468 -45.005498)
		(property "Reference" "C9105"
			(at 0 0 0)
			(layer "F.SilkS")
			(hide yes)
			(effects
				(font
					(size 1.27 1.27)
				)
			)
		)
		(property "Value" ""
			(at 0 0 0)
			(layer "F.Fab")
			(effects
				(font
					(size 1.27 1.27)
				)
			)
		)
		(duplicate_pad_numbers_are_jumpers no)
		(fp_line
			(start -0.299974 -0.150114)
			(end 0.299974 -0.150114)
			(stroke
				(width 0.1)
				(type default)
			)
			(layer "F.Fab")
		)
		(fp_line
			(start -0.299974 0.150114)
			(end -0.299974 -0.150114)
			(stroke
				(width 0.1)
				(type default)
			)
			(layer "F.Fab")
		)
		(fp_line
			(start 0.299974 -0.150114)
			(end 0.299974 0.150114)
			(stroke
				(width 0.1)
				(type default)
			)
			(layer "F.Fab")
		)
		(fp_line
			(start 0.299974 0.150114)
			(end -0.299974 0.150114)
			(stroke
				(width 0.1)
				(type default)
			)
			(layer "F.Fab")
		)
		(pad "1" smd rect
			(at -0.2667 0)
			(size 0.3048 0.381)
			(layers "F.Cu" "F.Mask" "F.Paste")
			(net "P3E_CPU1_P4_TX_C_DN<0>")
		)
		(pad "2" smd rect
			(at 0.2667 0)
			(size 0.3048 0.381)
			(layers "F.Cu" "F.Mask" "F.Paste")
			(net "P3E_CPU1_P4_TX_DN<0>")
		)
	)
)
